(kicad_pcb
	(version 20241229)
	(generator "pcbnew")
	(generator_version "9.0")
	(general
		(thickness 1.63)
		(legacy_teardrops no)
	)
	(paper "A4")
	(title_block
		(title "CM4 Baseboard")
		(date "2026-01-05")
		(rev "1.1.1")
		(company "Antmicro Ltd")
		(comment 1 "www.antmicro.com")
		(comment 9 "footprints 31-36 of 506")
	)
	(layers
		(0 "F.Cu" signal)
		(4 "In1.Cu" power)
		(6 "In2.Cu" power)
		(8 "In3.Cu" signal)
		(10 "In4.Cu" signal)
		(2 "B.Cu" signal)
		(9 "F.Adhes" user "F.Adhesive")
		(11 "B.Adhes" user "B.Adhesive")
		(13 "F.Paste" user)
		(15 "B.Paste" user)
		(5 "F.SilkS" user "F.Silkscreen")
		(7 "B.SilkS" user "B.Silkscreen")
		(1 "F.Mask" user)
		(3 "B.Mask" user)
		(17 "Dwgs.User" user "User.Drawings")
		(19 "Cmts.User" user "User.Comments")
		(21 "Eco1.User" user "User.Eco1")
		(23 "Eco2.User" user "User.Eco2")
		(25 "Edge.Cuts" user)
		(27 "Margin" user)
		(31 "F.CrtYd" user "F.Courtyard")
		(29 "B.CrtYd" user "B.Courtyard")
		(35 "F.Fab" user)
		(33 "B.Fab" user)
	)
	(footprint "antmicro-footprints:R_0402_1005Metric"
		(layer "F.Cu")
		(at 116.467962 134.9415 -90)
		(descr "Resistor SMD 0402")
		(tags "resistor SMD 0402")
		(property "Reference" "R510"
			(at -1.195 0.52 270)
			(layer "F.SilkS")
			(effects
				(font
					(size 0.7 0.7)
					(thickness 0.15)
				)
				(justify right bottom)
			)
		)
		(property "Value" "R_470R_0402"
			(at -1.011843 1.772047 90)
			(layer "F.Fab")
			(effects
				(font
					(size 0.7 0.7)
					(thickness 0.15)
				)
				(justify right bottom)
			)
		)
		(property "Datasheet" "https://www.bourns.com/docs/product-datasheets/cr.pdf"
			(at 0 0 270)
			(layer "F.Fab")
			(hide yes)
			(effects
				(font
					(size 1.27 1.27)
					(thickness 0.15)
				)
			)
		)
		(property "Manufacturer" "Bourns"
			(at 0 0 270)
			(unlocked yes)
			(layer "F.Fab")
			(hide yes)
			(effects
				(font
					(size 1 1)
					(thickness 0.15)
				)
			)
		)
		(property "MPN" "CR0402-FX-4700GLF"
			(at 0 0 270)
			(unlocked yes)
			(layer "F.Fab")
			(hide yes)
			(effects
				(font
					(size 1 1)
					(thickness 0.15)
				)
			)
		)
		(property "Val" "470R"
			(at 0 0 270)
			(unlocked yes)
			(layer "F.Fab")
			(hide yes)
			(effects
				(font
					(size 1 1)
					(thickness 0.15)
				)
			)
		)
		(property "License" "Apache-2.0"
			(at 0 0 270)
			(unlocked yes)
			(layer "F.Fab")
			(hide yes)
			(effects
				(font
					(size 1 1)
					(thickness 0.15)
				)
			)
		)
		(property "Author" "Antmicro"
			(at 0 0 270)
			(unlocked yes)
			(layer "F.Fab")
			(hide yes)
			(effects
				(font
					(size 1 1)
					(thickness 0.15)
				)
			)
		)
		(property "Tolerance" "1%"
			(at 0 0 270)
			(unlocked yes)
			(layer "F.Fab")
			(hide yes)
			(effects
				(font
					(size 1 1)
					(thickness 0.15)
				)
			)
		)
		(sheetname "/NVMe & microSD/")
		(sheetfile "nvme-micro-sd.kicad_sch")
		(attr smd)
		(fp_rect
			(start -0.925 -0.47)
			(end 0.925 0.47)
			(stroke
				(width 0.05)
				(type default)
			)
			(fill no)
			(layer "F.CrtYd")
		)
		(fp_rect
			(start -0.5 -0.25)
			(end 0.5 0.25)
			(stroke
				(width 0.15)
				(type solid)
			)
			(fill no)
			(layer "F.Fab")
		)
		(fp_text user "Author: Antmicro"
			(at -0.95 4.169 270)
			(layer "F.Fab")
			(effects
				(font
					(size 0.7 0.7)
					(thickness 0.15)
				)
				(justify left bottom)
			)
		)
		(fp_text user "License: Apache-2.0"
			(at -0.95 5.169 270)
			(layer "F.Fab")
			(effects
				(font
					(size 0.7 0.7)
					(thickness 0.15)
				)
				(justify left bottom)
			)
		)
		(fp_text user "${REFERENCE}"
			(at -0.95 3.168 270)
			(layer "F.Fab")
			(effects
				(font
					(size 0.7 0.7)
					(thickness 0.15)
				)
				(justify left bottom)
			)
		)
		(pad "1" smd roundrect
			(at -0.48 0 270)
			(size 0.59 0.64)
			(layers "F.Cu" "F.Mask" "F.Paste")
			(roundrect_rratio 0.25)
			(net 478 "Net-(D503-A)")
			(pintype "passive")
		)
		(pad "2" smd roundrect
			(at 0.48 0 270)
			(size 0.59 0.64)
			(layers "F.Cu" "F.Mask" "F.Paste")
			(roundrect_rratio 0.25)
			(net 65 "3V3_SSD")
			(pintype "passive")
		)
	)
	(footprint "antmicro-footprints:LED_0402_1005Metric_Y"
		(layer "F.Cu")
		(at 75.867962 136.0415 180)
		(property "Reference" "D911"
			(at 5.54752 -0.428183 0)
			(unlocked yes)
			(layer "F.SilkS")
			(effects
				(font
					(size 0.7 0.7)
					(thickness 0.15)
				)
				(justify left bottom)
			)
		)
		(property "Value" "LED_Y_0402_VLMY1500-GS08"
			(at 0.298 4.099 180)
			(unlocked yes)
			(layer "F.Fab")
			(effects
				(font
					(size 0.7 0.7)
					(thickness 0.15)
				)
				(justify left bottom)
			)
		)
		(property "Datasheet" "https://www.vishay.com/docs/82554/vlmo1500.pdf"
			(at 0 0 180)
			(layer "F.Fab")
			(hide yes)
			(effects
				(font
					(size 1.27 1.27)
					(thickness 0.15)
				)
			)
		)
		(property "MPN" "VLMY1500-GS08"
			(at 0 0 180)
			(unlocked yes)
			(layer "F.Fab")
			(hide yes)
			(effects
				(font
					(size 1 1)
					(thickness 0.15)
				)
			)
		)
		(property "Manufacturer" "Vishay"
			(at 0 0 180)
			(unlocked yes)
			(layer "F.Fab")
			(hide yes)
			(effects
				(font
					(size 1 1)
					(thickness 0.15)
				)
			)
		)
		(property "Author" "Antmicro"
			(at 0 0 180)
			(unlocked yes)
			(layer "F.Fab")
			(hide yes)
			(effects
				(font
					(size 1 1)
					(thickness 0.15)
				)
			)
		)
		(property "License" "Apache-2.0"
			(at 0 0 180)
			(unlocked yes)
			(layer "F.Fab")
			(hide yes)
			(effects
				(font
					(size 1 1)
					(thickness 0.15)
				)
			)
		)
		(property "Color" "Yellow"
			(at 0 0 180)
			(unlocked yes)
			(layer "F.Fab")
			(hide yes)
			(effects
				(font
					(size 1 1)
					(thickness 0.15)
				)
			)
		)
		(sheetname "/USB/")
		(sheetfile "usb.kicad_sch")
		(attr smd)
		(fp_line
			(start 0.175 0.4)
			(end -0.175 0.4)
			(stroke
				(width 0.15)
				(type solid)
			)
			(layer "F.SilkS")
		)
		(fp_line
			(start 0.175 -0.4)
			(end -0.175 -0.4)
			(stroke
				(width 0.15)
				(type solid)
			)
			(layer "F.SilkS")
		)
		(fp_line
			(start -0.9 0.4)
			(end -0.9 -0.4)
			(stroke
				(width 0.15)
				(type solid)
			)
			(layer "F.SilkS")
		)
		(fp_rect
			(start 0.925 0.47)
			(end -0.925 -0.47)
			(stroke
				(width 0.05)
				(type default)
			)
			(fill no)
			(layer "F.CrtYd")
		)
		(fp_line
			(start 0.501 0.26)
			(end 0.501 -0.248)
			(stroke
				(width 0.15)
				(type solid)
			)
			(layer "F.Fab")
		)
		(fp_line
			(start 0.501 0.26)
			(end 0.501 -0.248)
			(stroke
				(width 0.15)
				(type solid)
			)
			(layer "F.Fab")
		)
		(fp_line
			(start 0.501 -0.248)
			(end 0.172 -0.248)
			(stroke
				(width 0.15)
				(type solid)
			)
			(layer "F.Fab")
		)
		(fp_line
			(start 0.501 -0.248)
			(end -0.489 -0.248)
			(stroke
				(width 0.15)
				(type solid)
			)
			(layer "F.Fab")
		)
		(fp_line
			(start 0.228 0.202)
			(end 0.228 0)
			(stroke
				(width 0.15)
				(type solid)
			)
			(layer "F.Fab")
		)
		(fp_line
			(start 0.228 0)
			(end 0.228 -0.202)
			(stroke
				(width 0.15)
				(type solid)
			)
			(layer "F.Fab")
		)
		(fp_line
			(start 0.228 -0.202)
			(end -0.074 0)
			(stroke
				(width 0.15)
				(type solid)
			)
			(layer "F.Fab")
		)
		(fp_line
			(start 0.172 0.26)
			(end 0.501 0.26)
			(stroke
				(width 0.15)
				(type solid)
			)
			(layer "F.Fab")
		)
		(fp_line
			(start 0.172 -0.248)
			(end 0.172 0.26)
			(stroke
				(width 0.15)
				(type solid)
			)
			(layer "F.Fab")
		)
		(fp_line
			(start -0.074 0)
			(end 0.228 0.202)
			(stroke
				(width 0.15)
				(type solid)
			)
			(layer "F.Fab")
		)
		(fp_line
			(start -0.158 0.26)
			(end -0.158 -0.248)
			(stroke
				(width 0.15)
				(type solid)
			)
			(layer "F.Fab")
		)
		(fp_line
			(start -0.158 -0.248)
			(end -0.489 -0.248)
			(stroke
				(width 0.15)
				(type solid)
			)
			(layer "F.Fab")
		)
		(fp_line
			(start -0.173 0.202)
			(end -0.173 0.102)
			(stroke
				(width 0.15)
				(type solid)
			)
			(layer "F.Fab")
		)
		(fp_line
			(start -0.173 -0.202)
			(end -0.173 0.102)
			(stroke
				(width 0.15)
				(type solid)
			)
			(layer "F.Fab")
		)
		(fp_line
			(start -0.489 0.26)
			(end 0.501 0.26)
			(stroke
				(width 0.15)
				(type solid)
			)
			(layer "F.Fab")
		)
		(fp_line
			(start -0.489 0.26)
			(end -0.158 0.26)
			(stroke
				(width 0.15)
				(type solid)
			)
			(layer "F.Fab")
		)
		(fp_line
			(start -0.489 -0.248)
			(end -0.489 0.26)
			(stroke
				(width 0.15)
				(type solid)
			)
			(layer "F.Fab")
		)
		(fp_line
			(start -0.489 -0.248)
			(end -0.489 0.26)
			(stroke
				(width 0.15)
				(type solid)
			)
			(layer "F.Fab")
		)
		(fp_text user "License: Apache-2.0"
			(at -1.105 8.499 180)
			(layer "F.Fab")
			(effects
				(font
					(size 0.7 0.7)
					(thickness 0.15)
				)
				(justify left bottom)
			)
		)
		(fp_text user "Author: Antmicro"
			(at -1.105 7.299 180)
			(layer "F.Fab")
			(effects
				(font
					(size 0.7 0.7)
					(thickness 0.15)
				)
				(justify left bottom)
			)
		)
		(fp_text user "${REFERENCE}"
			(at -1.105 6.099 180)
			(unlocked yes)
			(layer "F.Fab")
			(effects
				(font
					(size 0.7 0.7)
					(thickness 0.15)
				)
				(justify left bottom)
			)
		)
		(pad "1" smd roundrect
			(at -0.48 0)
			(size 0.59 0.64)
			(layers "F.Cu" "F.Mask" "F.Paste")
			(roundrect_rratio 0.25)
			(net 486 "Net-(D911-C)")
			(pinfunction "C")
			(pintype "passive")
		)
		(pad "2" smd roundrect
			(at 0.48 0)
			(size 0.59 0.64)
			(layers "F.Cu" "F.Mask" "F.Paste")
			(roundrect_rratio 0.25)
			(net 487 "Net-(D911-A)")
			(pinfunction "A")
			(pintype "passive")
		)
	)
	(footprint "antmicro-footprints:R_0402_1005Metric"
		(layer "F.Cu")
		(at 73.507962 159.6765)
		(descr "Resistor SMD 0402")
		(tags "resistor SMD 0402")
		(property "Reference" "R325"
			(at -8.71 -0.61 0)
			(layer "F.SilkS")
			(effects
				(font
					(size 0.7 0.7)
					(thickness 0.15)
				)
				(justify left bottom)
			)
		)
		(property "Value" "R_1k_0402"
			(at -1.011843 1.772047 0)
			(layer "F.Fab")
			(effects
				(font
					(size 0.7 0.7)
					(thickness 0.15)
				)
				(justify left bottom)
			)
		)
		(property "Datasheet" "https://www.bourns.com/docs/product-datasheets/cr.pdf"
			(at 0 0 0)
			(layer "F.Fab")
			(hide yes)
			(effects
				(font
					(size 1.27 1.27)
					(thickness 0.15)
				)
			)
		)
		(property "MPN" "CR0402-FX-1001GLF"
			(at 0 0 0)
			(unlocked yes)
			(layer "F.Fab")
			(hide yes)
			(effects
				(font
					(size 1 1)
					(thickness 0.15)
				)
			)
		)
		(property "Manufacturer" "Bourns"
			(at 0 0 0)
			(unlocked yes)
			(layer "F.Fab")
			(hide yes)
			(effects
				(font
					(size 1 1)
					(thickness 0.15)
				)
			)
		)
		(property "License" "Apache-2.0"
			(at 0 0 0)
			(unlocked yes)
			(layer "F.Fab")
			(hide yes)
			(effects
				(font
					(size 1 1)
					(thickness 0.15)
				)
			)
		)
		(property "Author" "Antmicro"
			(at 0 0 0)
			(unlocked yes)
			(layer "F.Fab")
			(hide yes)
			(effects
				(font
					(size 1 1)
					(thickness 0.15)
				)
			)
		)
		(property "Val" "1k"
			(at 0 0 0)
			(unlocked yes)
			(layer "F.Fab")
			(hide yes)
			(effects
				(font
					(size 1 1)
					(thickness 0.15)
				)
			)
		)
		(property "Tolerance" "1%"
			(at 0 0 0)
			(unlocked yes)
			(layer "F.Fab")
			(hide yes)
			(effects
				(font
					(size 1 1)
					(thickness 0.15)
				)
			)
		)
		(sheetname "/Supply/")
		(sheetfile "supply.kicad_sch")
		(attr smd)
		(fp_rect
			(start -0.925 -0.47)
			(end 0.925 0.47)
			(stroke
				(width 0.05)
				(type default)
			)
			(fill no)
			(layer "F.CrtYd")
		)
		(fp_rect
			(start -0.5 -0.25)
			(end 0.5 0.25)
			(stroke
				(width 0.15)
				(type solid)
			)
			(fill no)
			(layer "F.Fab")
		)
		(fp_text user "${REFERENCE}"
			(at -0.95 3.168 0)
			(layer "F.Fab")
			(effects
				(font
					(size 0.7 0.7)
					(thickness 0.15)
				)
				(justify left bottom)
			)
		)
		(fp_text user "Author: Antmicro"
			(at -0.95 4.169 0)
			(layer "F.Fab")
			(effects
				(font
					(size 0.7 0.7)
					(thickness 0.15)
				)
				(justify left bottom)
			)
		)
		(fp_text user "License: Apache-2.0"
			(at -0.95 5.169 0)
			(layer "F.Fab")
			(effects
				(font
					(size 0.7 0.7)
					(thickness 0.15)
				)
				(justify left bottom)
			)
		)
		(pad "1" smd roundrect
			(at -0.48 0)
			(size 0.59 0.64)
			(layers "F.Cu" "F.Mask" "F.Paste")
			(roundrect_rratio 0.25)
			(net 474 "Net-(D304-A)")
			(pintype "passive")
		)
		(pad "2" smd roundrect
			(at 0.48 0)
			(size 0.59 0.64)
			(layers "F.Cu" "F.Mask" "F.Paste")
			(roundrect_rratio 0.25)
			(net 10 "+5V")
			(pintype "passive")
		)
	)
	(footprint "antmicro-footprints:R_0402_1005Metric"
		(layer "F.Cu")
		(at 76.167962 153.7915)
		(descr "Resistor SMD 0402")
		(tags "resistor SMD 0402")
		(property "Reference" "R229"
			(at 1.75 1.445 90)
			(layer "F.SilkS")
			(effects
				(font
					(size 0.7 0.7)
					(thickness 0.15)
				)
				(justify left bottom)
			)
		)
		(property "Value" "R_1k_0402"
			(at -1.011843 1.772047 0)
			(layer "F.Fab")
			(effects
				(font
					(size 0.7 0.7)
					(thickness 0.15)
				)
				(justify left bottom)
			)
		)
		(property "Datasheet" "https://www.bourns.com/docs/product-datasheets/cr.pdf"
			(at 0 0 0)
			(layer "F.Fab")
			(hide yes)
			(effects
				(font
					(size 1.27 1.27)
					(thickness 0.15)
				)
			)
		)
		(property "MPN" "CR0402-FX-1001GLF"
			(at 0 0 0)
			(unlocked yes)
			(layer "F.Fab")
			(hide yes)
			(effects
				(font
					(size 1 1)
					(thickness 0.15)
				)
			)
		)
		(property "Manufacturer" "Bourns"
			(at 0 0 0)
			(unlocked yes)
			(layer "F.Fab")
			(hide yes)
			(effects
				(font
					(size 1 1)
					(thickness 0.15)
				)
			)
		)
		(property "License" "Apache-2.0"
			(at 0 0 0)
			(unlocked yes)
			(layer "F.Fab")
			(hide yes)
			(effects
				(font
					(size 1 1)
					(thickness 0.15)
				)
			)
		)
		(property "Author" "Antmicro"
			(at 0 0 0)
			(unlocked yes)
			(layer "F.Fab")
			(hide yes)
			(effects
				(font
					(size 1 1)
					(thickness 0.15)
				)
			)
		)
		(property "Val" "1k"
			(at 0 0 0)
			(unlocked yes)
			(layer "F.Fab")
			(hide yes)
			(effects
				(font
					(size 1 1)
					(thickness 0.15)
				)
			)
		)
		(property "Tolerance" "1%"
			(at 0 0 0)
			(unlocked yes)
			(layer "F.Fab")
			(hide yes)
			(effects
				(font
					(size 1 1)
					(thickness 0.15)
				)
			)
		)
		(sheetname "/Compute module/")
		(sheetfile "compute-module.kicad_sch")
		(attr smd)
		(fp_rect
			(start -0.925 -0.47)
			(end 0.925 0.47)
			(stroke
				(width 0.05)
				(type default)
			)
			(fill no)
			(layer "F.CrtYd")
		)
		(fp_rect
			(start -0.5 -0.25)
			(end 0.5 0.25)
			(stroke
				(width 0.15)
				(type solid)
			)
			(fill no)
			(layer "F.Fab")
		)
		(fp_text user "${REFERENCE}"
			(at -0.95 3.168 0)
			(layer "F.Fab")
			(effects
				(font
					(size 0.7 0.7)
					(thickness 0.15)
				)
				(justify left bottom)
			)
		)
		(fp_text user "Author: Antmicro"
			(at -0.95 4.169 0)
			(layer "F.Fab")
			(effects
				(font
					(size 0.7 0.7)
					(thickness 0.15)
				)
				(justify left bottom)
			)
		)
		(fp_text user "License: Apache-2.0"
			(at -0.95 5.169 0)
			(layer "F.Fab")
			(effects
				(font
					(size 0.7 0.7)
					(thickness 0.15)
				)
				(justify left bottom)
			)
		)
		(pad "1" smd roundrect
			(at -0.48 0)
			(size 0.59 0.64)
			(layers "F.Cu" "F.Mask" "F.Paste")
			(roundrect_rratio 0.25)
			(net 500 "Net-(Q214-D)")
			(pintype "passive")
		)
		(pad "2" smd roundrect
			(at 0.48 0)
			(size 0.59 0.64)
			(layers "F.Cu" "F.Mask" "F.Paste")
			(roundrect_rratio 0.25)
			(net 466 "Net-(D206-C)")
			(pintype "passive")
		)
	)
	(footprint "antmicro-footprints:TP_SMD_0.75mm"
		(layer "F.Cu")
		(at 75.75 170.65 -90)
		(property "Reference" "TP801"
			(at -1.94 -8.305 0)
			(layer "F.SilkS")
			(effects
				(font
					(size 0.7 0.7)
					(thickness 0.15)
				)
				(justify left bottom)
			)
		)
		(property "Value" "TP_0.75mm_SMD"
			(at 0 1.2 270)
			(layer "F.Fab")
			(effects
				(font
					(size 0.7 0.7)
					(thickness 0.15)
				)
				(justify left bottom)
			)
		)
		(property "Author" "Antmicro"
			(at 0 0 270)
			(unlocked yes)
			(layer "F.Fab")
			(hide yes)
			(effects
				(font
					(size 1 1)
					(thickness 0.15)
				)
			)
		)
		(property "License" "Apache-2.0"
			(at 0 0 270)
			(unlocked yes)
			(layer "F.Fab")
			(hide yes)
			(effects
				(font
					(size 1 1)
					(thickness 0.15)
				)
			)
		)
		(property "MPN" ""
			(at 0 0 270)
			(unlocked yes)
			(layer "F.Fab")
			(hide yes)
			(effects
				(font
					(size 1 1)
					(thickness 0.15)
				)
			)
		)
		(property "Manufacturer" ""
			(at 0 0 270)
			(unlocked yes)
			(layer "F.Fab")
			(hide yes)
			(effects
				(font
					(size 1 1)
					(thickness 0.15)
				)
			)
		)
		(sheetname "/Peripherals/")
		(sheetfile "peripherals.kicad_sch")
		(attr exclude_from_pos_files exclude_from_bom)
		(fp_circle
			(center 0 0)
			(end 0.475 0)
			(stroke
				(width 0.05)
				(type default)
			)
			(fill no)
			(layer "F.CrtYd")
		)
		(fp_text user "${REFERENCE}"
			(at -0.4 2.7 270)
			(layer "F.Fab")
			(effects
				(font
					(size 0.7 0.7)
					(thickness 0.15)
				)
				(justify left bottom)
			)
		)
		(fp_text user "Author: Antmicro"
			(at -0.4 3.901 270)
			(layer "F.Fab")
			(effects
				(font
					(size 0.7 0.7)
					(thickness 0.15)
				)
				(justify left bottom)
			)
		)
		(fp_text user "License: Apache-2.0"
			(at -0.4 5.101 270)
			(layer "F.Fab")
			(effects
				(font
					(size 0.7 0.7)
					(thickness 0.15)
				)
				(justify left bottom)
			)
		)
		(pad "1" smd circle
			(at 0 0 270)
			(size 0.75 0.75)
			(layers "F.Cu" "F.Mask")
			(net 381 "Net-(U801-DCDC_EN)")
			(pinfunction "1")
			(pintype "passive")
		)
	)
	(footprint "antmicro-footprints:TP_SMD_0.75mm"
		(layer "F.Cu")
		(at 73.717962 133.1165)
		(property "Reference" "TP308"
			(at -9.217962 2.282028 0)
			(layer "F.SilkS")
			(effects
				(font
					(size 0.7 0.7)
					(thickness 0.15)
				)
				(justify left bottom)
			)
		)
		(property "Value" "TP_0.75mm_SMD"
			(at 0 1.2 0)
			(layer "F.Fab")
			(effects
				(font
					(size 0.7 0.7)
					(thickness 0.15)
				)
				(justify left bottom)
			)
		)
		(property "MPN" ""
			(at 0 0 0)
			(unlocked yes)
			(layer "F.Fab")
			(hide yes)
			(effects
				(font
					(size 1 1)
					(thickness 0.15)
				)
			)
		)
		(property "Manufacturer" ""
			(at 0 0 0)
			(unlocked yes)
			(layer "F.Fab")
			(hide yes)
			(effects
				(font
					(size 1 1)
					(thickness 0.15)
				)
			)
		)
		(property "Author" "Antmicro"
			(at 0 0 0)
			(unlocked yes)
			(layer "F.Fab")
			(hide yes)
			(effects
				(font
					(size 1 1)
					(thickness 0.15)
				)
			)
		)
		(property "License" "Apache-2.0"
			(at 0 0 0)
			(unlocked yes)
			(layer "F.Fab")
			(hide yes)
			(effects
				(font
					(size 1 1)
					(thickness 0.15)
				)
			)
		)
		(sheetname "/Supply/")
		(sheetfile "supply.kicad_sch")
		(attr exclude_from_pos_files exclude_from_bom)
		(fp_circle
			(center 0 0)
			(end 0.475 0)
			(stroke
				(width 0.05)
				(type default)
			)
			(fill no)
			(layer "F.CrtYd")
		)
		(fp_text user "${REFERENCE}"
			(at -0.4 2.7 0)
			(layer "F.Fab")
			(effects
				(font
					(size 0.7 0.7)
					(thickness 0.15)
				)
				(justify left bottom)
			)
		)
		(fp_text user "License: Apache-2.0"
			(at -0.4 5.101 0)
			(layer "F.Fab")
			(effects
				(font
					(size 0.7 0.7)
					(thickness 0.15)
				)
				(justify left bottom)
			)
		)
		(fp_text user "Author: Antmicro"
			(at -0.4 3.901 0)
			(layer "F.Fab")
			(effects
				(font
					(size 0.7 0.7)
					(thickness 0.15)
				)
				(justify left bottom)
			)
		)
		(pad "1" smd circle
			(at 0 0)
			(size 0.75 0.75)
			(layers "F.Cu" "F.Mask")
			(net 443 "/Supply/V_{BUS}")
			(pinfunction "1")
			(pintype "passive")
			(zone_connect 2)
		)
	)
)
